# BASEBOARD_FAB2 (Tioga Pass) — schematic netlist excerpt (pin names and nets, part order shuffled) for the footprints in the layout excerpt that follows; sources: Cadence DE-HDL packaged netlist, KiCad conversion of Wiwynn_Tioga_Pass_MB.brd

C2D18  CAP_A  22.0UF 4V 20% X6S  pkg 0603V  page 76 : A = PVCCMCP_CPU1 ; B = GND
C7G27  CAP  22UF 4V 20% X6S  pkg 0805LF  page 216 : A = PVDDQ_ABC ; B = GND
C8E17  CAP  1000PF 50V 10% EMPTY  pkg 0402LF  page 240 : A = PWRGD_P5V_STBY ; B = AGND_P3V3_STBY

(kicad_pcb
	(version 20260206)
	(generator "pcbnew")
	(generator_version "10.0")
	(general
		(thickness 1.6)
		(legacy_teardrops no)
	)
	(paper "A4")
	(title_block
		(title "Wiwynn_Tioga_Pass_MB.brd")
		(comment 1 "Tioga Pass / footprints 489-491 of 4770")
	)
	(layers
		(0 "F.Cu" signal "TOP")
		(4 "In1.Cu" signal "L2GND")
		(6 "In2.Cu" signal "L3")
		(8 "In3.Cu" signal "L4GND")
		(10 "In4.Cu" signal "L5")
		(12 "In5.Cu" signal "L6GND")
		(14 "In6.Cu" signal "L7VCC")
		(16 "In7.Cu" signal "L8VCC")
		(18 "In8.Cu" signal "L9GND")
		(20 "In9.Cu" signal "L10")
		(22 "In10.Cu" signal "L11GND")
		(24 "In11.Cu" signal "L12")
		(26 "In12.Cu" signal "L13GND")
		(2 "B.Cu" signal "BOTTOM")
		(9 "F.Adhes" user "F.Adhesive")
		(11 "B.Adhes" user "B.Adhesive")
		(13 "F.Paste" user "Package Geometry/Pastemask Top")
		(15 "B.Paste" user "Package Geometry/Pastemask Bottom")
		(5 "F.SilkS" user "Ref Des/Silkscreen Top")
		(7 "B.SilkS" user "Ref Des/Silkscreen Bottom")
		(1 "F.Mask" user "Board Geometry/Soldermask Top")
		(3 "B.Mask" user "Board Geometry/Soldermask Bottom")
		(17 "Dwgs.User" user "User.Drawings")
		(19 "Cmts.User" user "User.Comments")
		(21 "Eco1.User" user "User.Eco1")
		(23 "Eco2.User" user "User.Eco2")
		(25 "Edge.Cuts" user "Board Geometry/Outline")
		(27 "Margin" user)
		(31 "F.CrtYd" user "Package Geometry/Place Bound Top")
		(29 "B.CrtYd" user "Package Geometry/Place Bound Bottom")
		(35 "F.Fab" user "Ref Des/Assembly Top")
		(33 "B.Fab" user "Ref Des/Assembly Bottom")
	)
	(footprint ""
		(layer "F.Cu")
		(at 463.3849 -23.9903 180)
		(property "Reference" "C8E17"
			(at 0 0 180)
			(layer "F.SilkS")
			(hide yes)
			(effects
				(font
					(size 1.27 1.27)
				)
			)
		)
		(property "Value" ""
			(at 0 0 180)
			(layer "F.Fab")
			(effects
				(font
					(size 1.27 1.27)
				)
			)
		)
		(duplicate_pad_numbers_are_jumpers no)
		(fp_rect
			(start 0.3048 0.9906)
			(end -0.3048 -0.1016)
			(stroke
				(width 0)
				(type default)
			)
			(fill no)
			(layer "F.CrtYd")
		)
		(fp_line
			(start 0.3048 0.9906)
			(end 0.3048 -0.1016)
			(stroke
				(width 0.1)
				(type default)
			)
			(layer "F.Fab")
		)
		(fp_line
			(start 0.3048 -0.1016)
			(end -0.3048 -0.1016)
			(stroke
				(width 0.1)
				(type default)
			)
			(layer "F.Fab")
		)
		(fp_line
			(start -0.3048 0.9906)
			(end 0.3048 0.9906)
			(stroke
				(width 0.1)
				(type default)
			)
			(layer "F.Fab")
		)
		(fp_line
			(start -0.3048 -0.1016)
			(end -0.3048 0.9906)
			(stroke
				(width 0.1)
				(type default)
			)
			(layer "F.Fab")
		)
		(pad "1" smd rect
			(at 0 0 180)
			(size 0.508 0.508)
			(layers "F.Cu" "F.Mask" "F.Paste")
			(net "PWRGD_P5V_STBY")
		)
		(pad "2" smd rect
			(at 0 0.889 180)
			(size 0.508 0.508)
			(layers "F.Cu" "F.Mask" "F.Paste")
			(net "AGND_P3V3_STBY")
		)
		(zone
			(layer "F.Cu")
			(hatch none 0.5)
			(connect_pads
				(clearance 0)
			)
			(min_thickness 0.25)
			(keepout
				(tracks not_allowed)
				(vias allowed)
				(pads allowed)
				(copperpour not_allowed)
				(footprints allowed)
			)
			(placement
				(enabled no)
				(sheetname "")
			)
			(fill
				(thermal_gap 0.5)
				(thermal_bridge_width 0.5)
				(island_removal_mode 0)
			)
			(polygon
				(pts
					(xy 463.1309 -24.6253) (xy 463.1309 -24.2443) (xy 463.6389 -24.2443) (xy 463.6389 -24.6253)
				)
			)
		)
		(zone
			(layer "F.Cu")
			(hatch none 0.5)
			(connect_pads
				(clearance 0)
			)
			(min_thickness 0.25)
			(keepout
				(tracks allowed)
				(vias not_allowed)
				(pads allowed)
				(copperpour not_allowed)
				(footprints allowed)
			)
			(placement
				(enabled no)
				(sheetname "")
			)
			(fill
				(thermal_gap 0.5)
				(thermal_bridge_width 0.5)
				(island_removal_mode 0)
			)
			(polygon
				(pts
					(xy 463.1309 -24.6253) (xy 463.1309 -24.2443) (xy 463.6389 -24.2443) (xy 463.6389 -24.6253)
				)
			)
		)
	)
	(footprint ""
		(layer "F.Cu")
		(at 338.074 -11.684 90)
		(property "Reference" "C7G27"
			(at 0 0 90)
			(layer "F.SilkS")
			(hide yes)
			(effects
				(font
					(size 1.27 1.27)
				)
			)
		)
		(property "Value" ""
			(at 0 0 90)
			(layer "F.Fab")
			(effects
				(font
					(size 1.27 1.27)
				)
			)
		)
		(duplicate_pad_numbers_are_jumpers no)
		(fp_rect
			(start 0.7239 -0.2159)
			(end -0.7239 1.9939)
			(stroke
				(width 0)
				(type default)
			)
			(fill no)
			(layer "F.CrtYd")
		)
		(fp_line
			(start 0.7239 -0.2159)
			(end -0.7239 -0.2159)
			(stroke
				(width 0.1)
				(type default)
			)
			(layer "F.Fab")
		)
		(fp_line
			(start -0.7239 -0.2159)
			(end -0.7239 1.9939)
			(stroke
				(width 0.1)
				(type default)
			)
			(layer "F.Fab")
		)
		(fp_line
			(start 0.7239 1.9939)
			(end 0.7239 -0.2159)
			(stroke
				(width 0.1)
				(type default)
			)
			(layer "F.Fab")
		)
		(fp_line
			(start -0.7239 1.9939)
			(end 0.7239 1.9939)
			(stroke
				(width 0.1)
				(type default)
			)
			(layer "F.Fab")
		)
		(pad "1" smd rect
			(at 0 0 90)
			(size 1.27 1.016)
			(layers "F.Cu" "F.Mask" "F.Paste")
			(net "PVDDQ_ABC")
		)
		(pad "2" smd rect
			(at 0 1.778 90)
			(size 1.27 1.016)
			(layers "F.Cu" "F.Mask" "F.Paste")
			(net "GND")
		)
		(zone
			(layer "F.Cu")
			(hatch none 0.5)
			(connect_pads
				(clearance 0)
			)
			(min_thickness 0.25)
			(keepout
				(tracks not_allowed)
				(vias allowed)
				(pads allowed)
				(copperpour not_allowed)
				(footprints allowed)
			)
			(placement
				(enabled no)
				(sheetname "")
			)
			(fill
				(thermal_gap 0.5)
				(thermal_bridge_width 0.5)
				(island_removal_mode 0)
			)
			(polygon
				(pts
					(xy 338.582 -12.319) (xy 338.582 -11.049) (xy 339.344 -11.049) (xy 339.344 -12.319)
				)
			)
		)
	)
	(footprint ""
		(layer "F.Cu")
		(at 105.712768 -79.6036 180)
		(property "Reference" "C2D18"
			(at 0 0 180)
			(layer "F.SilkS")
			(hide yes)
			(effects
				(font
					(size 1.27 1.27)
				)
			)
		)
		(property "Value" ""
			(at 0 0 180)
			(layer "F.Fab")
			(effects
				(font
					(size 1.27 1.27)
				)
			)
		)
		(duplicate_pad_numbers_are_jumpers no)
		(fp_poly
			(pts
				(xy -0.4953 -0.2032) (xy 0.4953 -0.2032) (xy 0.4953 1.6002) (xy -0.4953 1.6002)
			)
			(stroke
				(width 0)
				(type default)
			)
			(fill no)
			(layer "F.CrtYd")
		)
		(fp_line
			(start 0.4953 1.6002)
			(end -0.4953 1.6002)
			(stroke
				(width 0.1)
				(type default)
			)
			(layer "F.Fab")
		)
		(fp_line
			(start 0.4953 -0.2032)
			(end 0.4953 1.6002)
			(stroke
				(width 0.1)
				(type default)
			)
			(layer "F.Fab")
		)
		(fp_line
			(start -0.4953 1.6002)
			(end -0.4953 -0.2032)
			(stroke
				(width 0.1)
				(type default)
			)
			(layer "F.Fab")
		)
		(fp_line
			(start -0.4953 -0.2032)
			(end 0.4953 -0.2032)
			(stroke
				(width 0.1)
				(type default)
			)
			(layer "F.Fab")
		)
		(pad "1" smd rect
			(at 0 0 180)
			(size 0.762 0.889)
			(layers "F.Cu" "F.Mask" "F.Paste")
			(net "PVCCMCP_CPU1")
		)
		(pad "2" smd rect
			(at 0 1.397 180)
			(size 0.762 0.889)
			(layers "F.Cu" "F.Mask" "F.Paste")
			(net "GND")
		)
		(zone
			(layer "F.Cu")
			(hatch none 0.5)
			(connect_pads
				(clearance 0)
			)
			(min_thickness 0.25)
			(keepout
				(tracks not_allowed)
				(vias allowed)
				(pads allowed)
				(copperpour not_allowed)
				(footprints allowed)
			)
			(placement
				(enabled no)
				(sheetname "")
			)
			(fill
				(thermal_gap 0.5)
				(thermal_bridge_width 0.5)
				(island_removal_mode 0)
			)
			(polygon
				(pts
					(xy 106.093768 -80.0481) (xy 105.331768 -80.0481) (xy 105.331768 -80.5561) (xy 106.093768 -80.5561)
				)
			)
		)
	)
)
